(kicad_pcb
	(version 20260206)
	(generator "pcbnew")
	(generator_version "10.0")
	(general
		(thickness 1.6)
		(legacy_teardrops no)
	)
	(paper "A4")
	(title_block
		(title "03242023_DA0F0TMBIJ0_F0T_Motherboard_J_brd_V01_OCP.brd")
		(comment 1 "Grand Teton / footprint 3039 of 6105 (U2), pads 3460-3566 of 4677")
	)
	(layers
		(0 "F.Cu" signal "TOP")
		(4 "In1.Cu" signal "GND")
		(6 "In2.Cu" signal "IN1")
		(8 "In3.Cu" signal "GND1")
		(10 "In4.Cu" signal "IN2")
		(12 "In5.Cu" signal "GND2")
		(14 "In6.Cu" signal "IN3")
		(16 "In7.Cu" signal "GND3")
		(18 "In8.Cu" signal "VCC")
		(20 "In9.Cu" signal "VCC1")
		(22 "In10.Cu" signal "GND4")
		(24 "In11.Cu" signal "IN4")
		(26 "In12.Cu" signal "GND5")
		(28 "In13.Cu" signal "IN5")
		(30 "In14.Cu" signal "GND6")
		(32 "In15.Cu" signal "IN6")
		(34 "In16.Cu" signal "GND7")
		(2 "B.Cu" signal "BOTTOM")
		(9 "F.Adhes" user "F.Adhesive")
		(11 "B.Adhes" user "B.Adhesive")
		(13 "F.Paste" user "Package Geometry/Pastemask Top")
		(15 "B.Paste" user "Package Geometry/Pastemask Bottom")
		(5 "F.SilkS" user "Ref Des/Silkscreen Top")
		(7 "B.SilkS" user "Ref Des/Silkscreen Bottom")
		(1 "F.Mask" user "Board Geometry/Soldermask Top")
		(3 "B.Mask" user "Board Geometry/Soldermask Bottom")
		(17 "Dwgs.User" user "User.Drawings")
		(19 "Cmts.User" user "User.Comments")
		(21 "Eco1.User" user "User.Eco1")
		(23 "Eco2.User" user "User.Eco2")
		(25 "Edge.Cuts" user "Board Geometry/Outline")
		(27 "Margin" user)
		(31 "F.CrtYd" user "Package Geometry/Place Bound Top")
		(29 "B.CrtYd" user "Package Geometry/Place Bound Bottom")
		(35 "F.Fab" user "Ref Des/Assembly Top")
		(33 "B.Fab" user "Ref Des/Assembly Bottom")
	)
	(footprint ""
		(layer "F.Cu")
		(at 359.870248 -251.76988 90)
		(property "Reference" "U2"
			(at -74.416158 -44.488608 0)
			(unlocked yes)
			(layer "F.SilkS")
			(effects
				(font
					(size 1.6002 1.1938)
					(thickness 0.1524)
				)
				(justify left)
			)
		)
		(property "Value" ""
			(at 0 0 90)
			(layer "F.Fab")
			(effects
				(font
					(size 1.27 1.27)
				)
			)
		)
		(duplicate_pad_numbers_are_jumpers no)
		(pad "EC76" smd circle
			(at 25.216612 20.965668 270)
			(size 0.4318 0.4318)
			(layers "F.Cu" "F.Mask" "F.Paste")
			(net "M_F_CPU0_SA_DQS_DP<0>")
		)
		(pad "EC78" smd circle
			(at 26.844498 20.965668 270)
			(size 0.4318 0.4318)
			(layers "F.Cu" "F.Mask" "F.Paste")
			(net "PVCCFA_EHV_FIVRA_CPU0")
		)
		(pad "EC80" smd circle
			(at 28.472384 20.965668 270)
			(size 0.4318 0.4318)
			(layers "F.Cu" "F.Mask" "F.Paste")
			(net "GND")
		)
		(pad "EC82" smd circle
			(at 30.100016 20.965668 270)
			(size 0.4318 0.4318)
			(layers "F.Cu" "F.Mask" "F.Paste")
			(net "GND")
		)
		(pad "EC84" smd circle
			(at 31.727902 20.965668 270)
			(size 0.4318 0.4318)
			(layers "F.Cu" "F.Mask" "F.Paste")
			(net "GND")
		)
		(pad "EC86" smd circle
			(at 33.355534 20.965668 270)
			(size 0.4318 0.4318)
			(layers "F.Cu" "F.Mask" "F.Paste")
			(net "P5E_CPU0_PE3_TX_DP<1>")
		)
		(pad "EC88" smd circle
			(at 34.98342 20.965668 270)
			(size 0.4318 0.4318)
			(layers "F.Cu" "F.Mask" "F.Paste")
			(net "GND")
		)
		(pad "EC90" smd circle
			(at 36.611306 20.965668 270)
			(size 0.4318 0.4318)
			(layers "F.Cu" "F.Mask" "F.Paste")
			(net "P5E_CPU0_PE3_RX_DN<2>")
		)
		(pad "ED2" smd oval
			(at -36.611306 21.325332 180)
			(size 0.381 0.4826)
			(drill
				(offset 0 -0.0508)
			)
			(layers "F.Cu" "F.Mask" "F.Paste")
			(net "UPI_CPU1_CPU0_P0P1_DP<2>")
		)
		(pad "ED4" smd circle
			(at -34.98342 21.325332 270)
			(size 0.4318 0.4318)
			(layers "F.Cu" "F.Mask" "F.Paste")
			(net "GND")
		)
		(pad "ED6" smd circle
			(at -33.355534 21.325332 270)
			(size 0.4318 0.4318)
			(layers "F.Cu" "F.Mask" "F.Paste")
			(net "UPI_CPU0_CPU1_P1P0_DP<1>")
		)
		(pad "ED8" smd circle
			(at -31.727902 21.325332 270)
			(size 0.4318 0.4318)
			(layers "F.Cu" "F.Mask" "F.Paste")
			(net "GND")
		)
		(pad "ED10" smd circle
			(at -30.100016 21.325332 270)
			(size 0.4318 0.4318)
			(layers "F.Cu" "F.Mask" "F.Paste")
			(net "P5E_CPU0_PE2_RX_DN<13>")
		)
		(pad "ED12" smd circle
			(at -28.472384 21.325332 270)
			(size 0.4318 0.4318)
			(layers "F.Cu" "F.Mask" "F.Paste")
			(net "GND")
		)
		(pad "ED14" smd circle
			(at -26.844498 21.325332 270)
			(size 0.4318 0.4318)
			(layers "F.Cu" "F.Mask" "F.Paste")
			(net "P5E_CPU0_PE2_TX_DP<14>")
		)
		(pad "ED16" smd circle
			(at -25.216612 21.325332 270)
			(size 0.4318 0.4318)
			(layers "F.Cu" "F.Mask" "F.Paste")
			(net "GND")
		)
		(pad "ED18" smd circle
			(at -23.58898 21.325332 270)
			(size 0.4318 0.4318)
			(layers "F.Cu" "F.Mask" "F.Paste")
			(net "GND")
		)
		(pad "ED20" smd circle
			(at -21.961094 21.325332 270)
			(size 0.4318 0.4318)
			(layers "F.Cu" "F.Mask" "F.Paste")
			(net "M_F_CPU0_SB_DQ<12>")
		)
		(pad "ED22" smd circle
			(at -20.333462 21.325332 270)
			(size 0.4318 0.4318)
			(layers "F.Cu" "F.Mask" "F.Paste")
			(net "M_F_CPU0_SB_DQ<9>")
		)
		(pad "ED24" smd circle
			(at -18.705576 21.325332 270)
			(size 0.4318 0.4318)
			(layers "F.Cu" "F.Mask" "F.Paste")
			(net "GND")
		)
		(pad "ED26" smd circle
			(at -17.07769 21.325332 270)
			(size 0.4318 0.4318)
			(layers "F.Cu" "F.Mask" "F.Paste")
			(net "M_E_CPU0_SB_DQ<4>")
		)
		(pad "ED28" smd circle
			(at -15.450058 21.325332 270)
			(size 0.4318 0.4318)
			(layers "F.Cu" "F.Mask" "F.Paste")
			(net "M_E_CPU0_SB_DQ<1>")
		)
		(pad "ED30" smd circle
			(at -13.822426 21.325332 270)
			(size 0.4318 0.4318)
			(layers "F.Cu" "F.Mask" "F.Paste")
			(net "GND")
		)
		(pad "ED32" smd circle
			(at -12.19454 21.325332 270)
			(size 0.4318 0.4318)
			(layers "F.Cu" "F.Mask" "F.Paste")
			(net "M_F_CPU0_SB_CB<0>")
		)
		(pad "ED34" smd circle
			(at -10.566654 21.325332 270)
			(size 0.4318 0.4318)
			(layers "F.Cu" "F.Mask" "F.Paste")
			(net "M_F_CPU0_SB_CB<5>")
		)
		(pad "ED36" smd circle
			(at -8.939022 21.325332 270)
			(size 0.4318 0.4318)
			(layers "F.Cu" "F.Mask" "F.Paste")
			(net "GND")
		)
		(pad "ED38" smd circle
			(at -7.311136 21.325332 270)
			(size 0.4318 0.4318)
			(layers "F.Cu" "F.Mask" "F.Paste")
			(net "M_F_CPU0_SB_CS_N<2>")
		)
		(pad "ED40" smd circle
			(at -5.68325 21.325332 270)
			(size 0.4318 0.4318)
			(layers "F.Cu" "F.Mask" "F.Paste")
			(net "M_F_CPU0_SB_CA<4>")
		)
		(pad "ED42" smd circle
			(at -4.055618 21.325332 270)
			(size 0.4318 0.4318)
			(layers "F.Cu" "F.Mask" "F.Paste")
			(net "GND")
		)
		(pad "ED44" smd circle
			(at -2.427732 21.325332 270)
			(size 0.4318 0.4318)
			(layers "F.Cu" "F.Mask" "F.Paste")
			(net "M_E_CPU0_SA_CA<6>")
		)
		(pad "ED47" smd circle
			(at 1.613916 21.435314 270)
			(size 0.4318 0.4318)
			(layers "F.Cu" "F.Mask" "F.Paste")
			(net "M_H_CPU0_SB_RSP<1>")
		)
		(pad "ED49" smd circle
			(at 3.241802 21.435314 270)
			(size 0.4318 0.4318)
			(layers "F.Cu" "F.Mask" "F.Paste")
			(net "GND")
		)
		(pad "ED51" smd circle
			(at 4.869434 21.435314 270)
			(size 0.4318 0.4318)
			(layers "F.Cu" "F.Mask" "F.Paste")
			(net "M_F_CPU0_SA_CA<2>")
		)
		(pad "ED53" smd circle
			(at 6.49732 21.435314 270)
			(size 0.4318 0.4318)
			(layers "F.Cu" "F.Mask" "F.Paste")
			(net "M_F_CPU0_SA_CS_N<3>")
		)
		(pad "ED55" smd circle
			(at 8.124952 21.435314 270)
			(size 0.4318 0.4318)
			(layers "F.Cu" "F.Mask" "F.Paste")
			(net "GND")
		)
		(pad "ED57" smd circle
			(at 9.752838 21.435314 270)
			(size 0.4318 0.4318)
			(layers "F.Cu" "F.Mask" "F.Paste")
			(net "M_F_CPU0_SA_CB<4>")
		)
		(pad "ED59" smd circle
			(at 11.380724 21.435314 270)
			(size 0.4318 0.4318)
			(layers "F.Cu" "F.Mask" "F.Paste")
			(net "M_F_CPU0_SA_CB<1>")
		)
		(pad "ED61" smd circle
			(at 13.008356 21.435314 270)
			(size 0.4318 0.4318)
			(layers "F.Cu" "F.Mask" "F.Paste")
			(net "GND")
		)
		(pad "ED63" smd circle
			(at 14.635988 21.435314 270)
			(size 0.4318 0.4318)
			(layers "F.Cu" "F.Mask" "F.Paste")
			(net "M_F_CPU0_SA_DQ<20>")
		)
		(pad "ED65" smd circle
			(at 16.263874 21.435314 270)
			(size 0.4318 0.4318)
			(layers "F.Cu" "F.Mask" "F.Paste")
			(net "M_F_CPU0_SA_DQ<17>")
		)
		(pad "ED67" smd circle
			(at 17.89176 21.435314 270)
			(size 0.4318 0.4318)
			(layers "F.Cu" "F.Mask" "F.Paste")
			(net "GND")
		)
		(pad "ED69" smd circle
			(at 19.519392 21.435314 270)
			(size 0.4318 0.4318)
			(layers "F.Cu" "F.Mask" "F.Paste")
			(net "M_E_CPU0_SA_DQ<12>")
		)
		(pad "ED71" smd circle
			(at 21.147278 21.435314 270)
			(size 0.4318 0.4318)
			(layers "F.Cu" "F.Mask" "F.Paste")
			(net "M_E_CPU0_SA_DQ<9>")
		)
		(pad "ED73" smd circle
			(at 22.77491 21.435314 270)
			(size 0.4318 0.4318)
			(layers "F.Cu" "F.Mask" "F.Paste")
			(net "GND")
		)
		(pad "ED75" smd circle
			(at 24.402796 21.435314 270)
			(size 0.4318 0.4318)
			(layers "F.Cu" "F.Mask" "F.Paste")
			(net "M_F_CPU0_SA_DQ<4>")
		)
		(pad "ED77" smd circle
			(at 26.030682 21.435314 270)
			(size 0.4318 0.4318)
			(layers "F.Cu" "F.Mask" "F.Paste")
			(net "M_F_CPU0_SA_DQ<2>")
		)
		(pad "ED79" smd circle
			(at 27.658314 21.435314 270)
			(size 0.4318 0.4318)
			(layers "F.Cu" "F.Mask" "F.Paste")
			(net "PVCCFA_EHV_FIVRA_CPU0")
		)
		(pad "ED81" smd circle
			(at 29.2862 21.435314 270)
			(size 0.4318 0.4318)
			(layers "F.Cu" "F.Mask" "F.Paste")
			(net "GND")
		)
		(pad "ED83" smd circle
			(at 30.914086 21.435314 270)
			(size 0.4318 0.4318)
			(layers "F.Cu" "F.Mask" "F.Paste")
			(net "GND")
		)
		(pad "ED85" smd circle
			(at 32.541718 21.435314 270)
			(size 0.4318 0.4318)
			(layers "F.Cu" "F.Mask" "F.Paste")
			(net "PVCCFA_EHV_FIVRA_CPU0")
		)
		(pad "ED87" smd circle
			(at 34.169604 21.435314 270)
			(size 0.4318 0.4318)
			(layers "F.Cu" "F.Mask" "F.Paste")
			(net "P5E_CPU0_PE3_TX_DP<0>")
		)
		(pad "ED89" smd circle
			(at 35.797236 21.435314 270)
			(size 0.4318 0.4318)
			(layers "F.Cu" "F.Mask" "F.Paste")
			(net "PVCCFA_EHV_FIVRA_CPU0")
		)
		(pad "ED91" smd oval
			(at 37.425122 21.435314)
			(size 0.381 0.4826)
			(drill
				(offset 0 -0.0508)
			)
			(layers "F.Cu" "F.Mask" "F.Paste")
			(net "P5E_CPU0_PE3_RX_DN<1>")
		)
		(pad "EE3" smd circle
			(at -35.797236 21.795486 270)
			(size 0.4318 0.4318)
			(layers "F.Cu" "F.Mask" "F.Paste")
			(net "UPI_CPU1_CPU0_P0P1_DN<1>")
		)
		(pad "EE5" smd circle
			(at -34.169604 21.795486 270)
			(size 0.4318 0.4318)
			(layers "F.Cu" "F.Mask" "F.Paste")
			(net "UPI_CPU0_CPU1_P1P0_DP<0>")
		)
		(pad "EE7" smd circle
			(at -32.541718 21.795486 270)
			(size 0.4318 0.4318)
			(layers "F.Cu" "F.Mask" "F.Paste")
			(net "PVCCFA_EHV_FIVRA_CPU0")
		)
		(pad "EE9" smd circle
			(at -30.914086 21.795486 270)
			(size 0.4318 0.4318)
			(layers "F.Cu" "F.Mask" "F.Paste")
			(net "P5E_CPU0_PE2_RX_DN<14>")
		)
		(pad "EE11" smd circle
			(at -29.2862 21.795486 270)
			(size 0.4318 0.4318)
			(layers "F.Cu" "F.Mask" "F.Paste")
			(net "PVCCFA_EHV_FIVRA_CPU0")
		)
		(pad "EE13" smd circle
			(at -27.658314 21.795486 270)
			(size 0.4318 0.4318)
			(layers "F.Cu" "F.Mask" "F.Paste")
			(net "P5E_CPU0_PE2_TX_DN<14>")
		)
		(pad "EE15" smd circle
			(at -26.030682 21.795486 270)
			(size 0.4318 0.4318)
			(layers "F.Cu" "F.Mask" "F.Paste")
			(net "PVCCFA_EHV_FIVRA_CPU0")
		)
		(pad "EE17" smd circle
			(at -24.402796 21.795486 270)
			(size 0.4318 0.4318)
			(layers "F.Cu" "F.Mask" "F.Paste")
			(net "GND")
		)
		(pad "EE19" smd circle
			(at -22.77491 21.795486 270)
			(size 0.4318 0.4318)
			(layers "F.Cu" "F.Mask" "F.Paste")
			(net "M_F_CPU0_SB_DQ<13>")
		)
		(pad "EE21" smd circle
			(at -21.147278 21.795486 270)
			(size 0.4318 0.4318)
			(layers "F.Cu" "F.Mask" "F.Paste")
			(net "M_F_CPU0_SB_DQS_DN<1>")
		)
		(pad "EE23" smd circle
			(at -19.519392 21.795486 270)
			(size 0.4318 0.4318)
			(layers "F.Cu" "F.Mask" "F.Paste")
			(net "M_F_CPU0_SB_DQ<8>")
		)
		(pad "EE25" smd circle
			(at -17.89176 21.795486 270)
			(size 0.4318 0.4318)
			(layers "F.Cu" "F.Mask" "F.Paste")
			(net "M_E_CPU0_SB_DQ<5>")
		)
		(pad "EE27" smd circle
			(at -16.263874 21.795486 270)
			(size 0.4318 0.4318)
			(layers "F.Cu" "F.Mask" "F.Paste")
			(net "M_E_CPU0_SB_DQS_DN<0>")
		)
		(pad "EE29" smd circle
			(at -14.635988 21.795486 270)
			(size 0.4318 0.4318)
			(layers "F.Cu" "F.Mask" "F.Paste")
			(net "M_E_CPU0_SB_DQ<0>")
		)
		(pad "EE31" smd circle
			(at -13.008356 21.795486 270)
			(size 0.4318 0.4318)
			(layers "F.Cu" "F.Mask" "F.Paste")
			(net "M_F_CPU0_SB_CB<1>")
		)
		(pad "EE33" smd circle
			(at -11.380724 21.795486 270)
			(size 0.4318 0.4318)
			(layers "F.Cu" "F.Mask" "F.Paste")
			(net "M_F_CPU0_SB_DQS_DN<9>")
		)
		(pad "EE35" smd circle
			(at -9.752838 21.795486 270)
			(size 0.4318 0.4318)
			(layers "F.Cu" "F.Mask" "F.Paste")
			(net "M_F_CPU0_SB_CB<4>")
		)
		(pad "EE37" smd circle
			(at -8.124952 21.795486 270)
			(size 0.4318 0.4318)
			(layers "F.Cu" "F.Mask" "F.Paste")
			(net "M_F_CPU0_SB_CS_N<3>")
		)
		(pad "EE39" smd circle
			(at -6.49732 21.795486 270)
			(size 0.4318 0.4318)
			(layers "F.Cu" "F.Mask" "F.Paste")
			(net "GND")
		)
		(pad "EE41" smd circle
			(at -4.869434 21.795486 270)
			(size 0.4318 0.4318)
			(layers "F.Cu" "F.Mask" "F.Paste")
			(net "M_F_CPU0_SB_CA<2>")
		)
		(pad "EE43" smd circle
			(at -3.241802 21.795486 270)
			(size 0.4318 0.4318)
			(layers "F.Cu" "F.Mask" "F.Paste")
			(net "M_E_CPU0_SA_PAR")
		)
		(pad "EE45" smd circle
			(at -1.613916 21.795486 270)
			(size 0.4318 0.4318)
			(layers "F.Cu" "F.Mask" "F.Paste")
			(net "M_E_CPU0_CLK_DN<1>")
		)
		(pad "EE48" smd circle
			(at 2.427732 21.905468 270)
			(size 0.4318 0.4318)
			(layers "F.Cu" "F.Mask" "F.Paste")
			(net "M_H_CPU0_SB_RSP<0>")
		)
		(pad "EE50" smd circle
			(at 4.055618 21.905468 270)
			(size 0.4318 0.4318)
			(layers "F.Cu" "F.Mask" "F.Paste")
			(net "M_F_CPU0_SA_CA<4>")
		)
		(pad "EE52" smd circle
			(at 5.68325 21.905468 270)
			(size 0.4318 0.4318)
			(layers "F.Cu" "F.Mask" "F.Paste")
			(net "GND")
		)
		(pad "EE54" smd circle
			(at 7.311136 21.905468 270)
			(size 0.4318 0.4318)
			(layers "F.Cu" "F.Mask" "F.Paste")
			(net "M_F_CPU0_SA_CS_N<2>")
		)
		(pad "EE56" smd circle
			(at 8.939022 21.905468 270)
			(size 0.4318 0.4318)
			(layers "F.Cu" "F.Mask" "F.Paste")
			(net "M_F_CPU0_SA_CB<5>")
		)
		(pad "EE58" smd circle
			(at 10.566654 21.905468 270)
			(size 0.4318 0.4318)
			(layers "F.Cu" "F.Mask" "F.Paste")
			(net "M_F_CPU0_SA_DQS_DN<4>")
		)
		(pad "EE60" smd circle
			(at 12.19454 21.905468 270)
			(size 0.4318 0.4318)
			(layers "F.Cu" "F.Mask" "F.Paste")
			(net "M_F_CPU0_SA_CB<0>")
		)
		(pad "EE62" smd circle
			(at 13.822426 21.905468 270)
			(size 0.4318 0.4318)
			(layers "F.Cu" "F.Mask" "F.Paste")
			(net "M_F_CPU0_SA_DQ<21>")
		)
		(pad "EE64" smd circle
			(at 15.450058 21.905468 270)
			(size 0.4318 0.4318)
			(layers "F.Cu" "F.Mask" "F.Paste")
			(net "M_F_CPU0_SA_DQS_DP<2>")
		)
		(pad "EE66" smd circle
			(at 17.07769 21.905468 270)
			(size 0.4318 0.4318)
			(layers "F.Cu" "F.Mask" "F.Paste")
			(net "M_F_CPU0_SA_DQ<16>")
		)
		(pad "EE68" smd circle
			(at 18.705576 21.905468 270)
			(size 0.4318 0.4318)
			(layers "F.Cu" "F.Mask" "F.Paste")
			(net "M_E_CPU0_SA_DQ<13>")
		)
		(pad "EE70" smd circle
			(at 20.333462 21.905468 270)
			(size 0.4318 0.4318)
			(layers "F.Cu" "F.Mask" "F.Paste")
			(net "M_E_CPU0_SA_DQS_DP<1>")
		)
		(pad "EE72" smd circle
			(at 21.961094 21.905468 270)
			(size 0.4318 0.4318)
			(layers "F.Cu" "F.Mask" "F.Paste")
			(net "M_E_CPU0_SA_DQ<8>")
		)
		(pad "EE74" smd circle
			(at 23.58898 21.905468 270)
			(size 0.4318 0.4318)
			(layers "F.Cu" "F.Mask" "F.Paste")
			(net "M_F_CPU0_SA_DQ<5>")
		)
		(pad "EE76" smd circle
			(at 25.216612 21.905468 270)
			(size 0.4318 0.4318)
			(layers "F.Cu" "F.Mask" "F.Paste")
			(net "M_F_CPU0_SA_DQS_DN<0>")
		)
		(pad "EE78" smd circle
			(at 26.844498 21.905468 270)
			(size 0.4318 0.4318)
			(layers "F.Cu" "F.Mask" "F.Paste")
			(net "GND")
		)
		(pad "EE80" smd circle
			(at 28.472384 21.905468 270)
			(size 0.4318 0.4318)
			(layers "F.Cu" "F.Mask" "F.Paste")
			(net "GND")
		)
		(pad "EE82" smd circle
			(at 30.100016 21.905468 270)
			(size 0.4318 0.4318)
			(layers "F.Cu" "F.Mask" "F.Paste")
			(net "GND")
		)
		(pad "EE84" smd circle
			(at 31.727902 21.905468 270)
			(size 0.4318 0.4318)
			(layers "F.Cu" "F.Mask" "F.Paste")
			(net "PVCCFA_EHV_FIVRA_CPU0")
		)
		(pad "EE86" smd circle
			(at 33.355534 21.905468 270)
			(size 0.4318 0.4318)
			(layers "F.Cu" "F.Mask" "F.Paste")
			(net "P5E_CPU0_PE3_TX_DN<0>")
		)
		(pad "EE88" smd circle
			(at 34.98342 21.905468 270)
			(size 0.4318 0.4318)
			(layers "F.Cu" "F.Mask" "F.Paste")
			(net "GND")
		)
		(pad "EE90" smd oval
			(at 36.611306 21.905468)
			(size 0.381 0.4826)
			(drill
				(offset 0 -0.0508)
			)
			(layers "F.Cu" "F.Mask" "F.Paste")
			(net "P5E_CPU0_PE3_RX_DP<1>")
		)
		(pad "EF2" smd oval
			(at -36.611306 22.265386 180)
			(size 0.381 0.4826)
			(drill
				(offset 0 -0.0508)
			)
			(layers "F.Cu" "F.Mask" "F.Paste")
			(net "GND")
		)
		(pad "EF4" smd circle
			(at -34.98342 22.265386 270)
			(size 0.4318 0.4318)
			(layers "F.Cu" "F.Mask" "F.Paste")
			(net "GND")
		)
		(pad "EF6" smd circle
			(at -33.355534 22.265386 270)
			(size 0.4318 0.4318)
			(layers "F.Cu" "F.Mask" "F.Paste")
			(net "UPI_CPU0_CPU1_P1P0_DN<0>")
		)
		(pad "EF8" smd circle
			(at -31.727902 22.265386 270)
			(size 0.4318 0.4318)
			(layers "F.Cu" "F.Mask" "F.Paste")
			(net "GND")
		)
		(pad "EF10" smd circle
			(at -30.100016 22.265386 270)
			(size 0.4318 0.4318)
			(layers "F.Cu" "F.Mask" "F.Paste")
			(net "P5E_CPU0_PE2_RX_DP<14>")
		)
		(pad "EF12" smd circle
			(at -28.472384 22.265386 270)
			(size 0.4318 0.4318)
			(layers "F.Cu" "F.Mask" "F.Paste")
			(net "GND")
		)
		(pad "EF14" smd circle
			(at -26.844498 22.265386 270)
			(size 0.4318 0.4318)
			(layers "F.Cu" "F.Mask" "F.Paste")
			(net "P5E_CPU0_PE2_TX_DN<15>")
		)
		(pad "EF16" smd circle
			(at -25.216612 22.265386 270)
			(size 0.4318 0.4318)
			(layers "F.Cu" "F.Mask" "F.Paste")
			(net "GND")
		)
		(pad "EF18" smd circle
			(at -23.58898 22.265386 270)
			(size 0.4318 0.4318)
			(layers "F.Cu" "F.Mask" "F.Paste")
			(net "GND")
		)
		(pad "EF20" smd circle
			(at -21.961094 22.265386 270)
			(size 0.4318 0.4318)
			(layers "F.Cu" "F.Mask" "F.Paste")
			(net "GND")
		)
	)
)
